FILE_TYPE = CONNECTIVITY;
{Allegro Design Entry HDL 17.4-2019 S026 (4007227) 1/17/2022}
"PAGE_NUMBER" = 170;
0"NC";
1"GND\g";
2"GND\g";
3"GND\g";
4"GND\g";
5"GND\g";
6"GND\g";
7"GND\g";
8"GND\g";
9"GND\g";
10"GND\g";
11"GND\g";
12"SW_P12V_AUX_PVDDCR_CPU0_P0_FLT\g";
13"PVDDCR_CPU0_P0_VOS3";
14"SW_PVDDCR_CPU0_P0_SW3";
15"SW_PVDDCR_CPU0_P0_PH3";
16"SW_PVDDCR_CPU0_P0_BOOT3";
17"PVDDCR_CPU0_P0_PVCC\g";
18"GND\g";
19"PVDDCR_CPU0_P0_PVCC\g";
20"GND\g";
21"GND\g";
22"GND\g";
23"PVDDCR_CPU0_P0\g";
24"GND\g";
25"SW_P12V_AUX_PVDDCR_CPU0_P0_FLT\g";
26"GND\g";
27"PVDDCR_CPU0_P0\g";
28"SW_PVDDCR_CPU0_P0_BOOT3_RC";
29"SW_PVDDCR_CPU0_P0_BOOT4";
30"SW_PVDDCR_CPU0_P0_BOOT4_RC";
31"SW_PVDDCR_CPU0_P0_PH4";
32"SW_PVDDCR_CPU0_P0_SW4_RC";
33"SW_PVDDCR_CPU0_P0_SW4";
34"IND_CPU0_P0_CPL3";
35"IND_CPU0_P0_CPL2";
36"IND_CPU0_P0_CPL3";
37"SW_PVDDCR_CPU0_P0_SW3_RC";
38"NC_PVDDCR_CPU0_P0_GL2_3";
39"NC_PVDDCR_CPU0_P0_GL1_3";
40"PVDDCR_CPU0_P0_VCC3";
41"PVDDCR_CPU0_P0_PWM3";
42"PVDDCR_CPU0_P0_TEMP0";
43"PVDDCR_CPU0_P0_IMON3";
44"NC_PVDDCR_CPU0_P0_DNC3";
45"PVDDCR_CPU0_P0_LSET3";
46"PVDDCR_CPU0_P0_VCCS";
47"PVDDCR_CPU0_P0_VOS4";
48"NC_PVDDCR_CPU0_P0_GL1_4";
49"NC_PVDDCR_CPU0_P0_GL2_4";
50"PVDDCR_CPU0_P0_VCC4";
51"PVDDCR_CPU0_P0_IMON4";
52"PVDDCR_CPU0_P0_TEMP0";
53"NC_PVDDCR_CPU0_P0_DNC4";
54"PVDDCR_CPU0_P0_LSET4";
55"PVDDCR_CPU0_P0_PWM4";
56"PVDDCR_CPU0_P0_VCCS";
%"Q_RES"
"1","(-6950,1200)","0","pure_quanta","I11";
;
LOCATION"PR347"
$SEC"1"
CDS_SEC"1"
PACK_TYPE"0402LF"
VALUE"8.87K"
TOLERANCE"1%"
MATERIAL"EMPTY"
WATTAGE"1/16W"
CDS_LIB"pure_quanta"
PART_NUMBER"CS28872FB01";
"B"
$PN"2"54;
"A"
$PN"1"9;
%"Q_RES"
"2","(-7250,2400)","0","pure_quanta","I12";
;
LOCATION"PR345"
$SEC"1"
CDS_SEC"1"
PACK_TYPE"0402LF"
VALUE"2.2"
TOLERANCE"1%"
MATERIAL"CHIP"
WATTAGE"1/16W"
CDS_LIB"pure_quanta"
PART_NUMBER"CS-2202FB01";
"A"
$PN"1"17;
"B"
$PN"2"50;
%"VCC_CORE"
"1","(-7250,2800)","0","pure_quanta_power","I13";
;
HDL_POWER"PVDDCR_CPU0_P0_PVCC"
CDS_LIB"pure_quanta_power";
"A"17;
%"UNIVERSAL_GND"
"1","(-6900,2150)","0","pure_quanta_power","I14";
;
CDS_LIB"pure_quanta_power"
HDL_POWER"GND";
"A"1;
%"Q_CAP"
"1","(-6900,2425)","0","pure_quanta","I15";
;
LOCATION"PC549_C0P0_4"
$SEC"1"
CDS_SEC"1"
MATERIAL"X6S"
VALUE"2.2UF"
VOLTAGE"10V"
PACK_TYPE"C0402"
TOLERANCE"10%"
CDS_LIB"pure_quanta"
PART_NUMBER"CH5222KEB01";
"B"
$PN"2"1;
"A"
$PN"1"17;
%"UNIVERSAL_GND"
"1","(-5225,750)","0","pure_quanta_power","I16";
;
CDS_LIB"pure_quanta_power"
HDL_POWER"GND";
"A"18;
%"UNIVERSAL_GND"
"1","(-4300,650)","0","pure_quanta_power","I17";
;
CDS_LIB"pure_quanta_power"
HDL_POWER"GND";
"A"2;
%"Q_RES"
"2","(-4300,875)","0","pure_quanta","I18";
;
LOCATION"PR499"
$SEC"1"
CDS_SEC"1"
WATTAGE"1/8W"
MATERIAL"EMPTY"
TOLERANCE"1%"
VALUE"1.5"
PACK_TYPE"0402LF"
CDS_LIB"pure_quanta"
PART_NUMBER"CS-1504FB00";
"A"
$PN"1"32;
"B"
$PN"2"2;
%"Q_CAP"
"1","(-4300,1325)","0","pure_quanta","I19";
;
LOCATION"PC181"
$SEC"1"
CDS_SEC"1"
MATERIAL"EMPTY"
PACK_TYPE"C0402"
VALUE"560PF"
VOLTAGE"50V"
TOLERANCE"10%"
CDS_LIB"pure_quanta"
PART_NUMBER"CH1566K1B09";
"B"
$PN"2"32;
"A"
$PN"1"33;
%"Q_CAP"
"1","(-7600,1225)","0","pure_quanta","I2";
;
LOCATION"PC545_4"
$SEC"1"
CDS_SEC"1"
MATERIAL"X7R"
TOLERANCE"10%"
VALUE"0.1UF"
VOLTAGE"25V"
PACK_TYPE"0402"
CDS_LIB"pure_quanta"
PART_NUMBER"CH4104K1B00";
"B"
$PN"2"5;
"A"
$PN"1"56;
%"Q_RES"
"1","(-4375,1850)","0","pure_quanta","I20";
;
LOCATION"PR349"
$SEC"1"
CDS_SEC"1"
VALUE"5.6"
PACK_TYPE"0402LF"
TOLERANCE"1%"
MATERIAL"CHIP"
WATTAGE"1/16W"
CDS_LIB"pure_quanta"
PART_NUMBER"CS-5602FB01";
"B"
$PN"2"30;
"A"
$PN"1"29;
%"Q_CAP"
"1","(-5100,2400)","0","pure_quanta","I21";
;
LOCATION"PC551_4"
$SEC"1"
CDS_SEC"1"
MATERIAL"X7R"
TOLERANCE"10%"
VALUE"0.1UF"
VOLTAGE"25V"
PACK_TYPE"0402"
CDS_LIB"pure_quanta"
PART_NUMBER"CH4104K1B00";
"B"
$PN"2"11;
"A"
$PN"1"12;
%"Q_CAP"
"1","(-4725,2400)","0","pure_quanta","I22";
;
LOCATION"PC553_4"
$SEC"1"
CDS_SEC"1"
MATERIAL"X6S"
TOLERANCE"10%"
VOLTAGE"25V"
VALUE"1UF"
PACK_TYPE"C0402"
CDS_LIB"pure_quanta"
PART_NUMBER"CH5104KEB02";
"B"
$PN"2"11;
"A"
$PN"1"12;
%"Q_CAP"
"1","(-4400,2400)","0","pure_quanta","I23";
;
LOCATION"PC555_4"
$SEC"1"
CDS_SEC"1"
TOLERANCE"20%"
MATERIAL"X6S"
PACK_TYPE"C0805"
VOLTAGE"16V"
VALUE"22UF"
CDS_LIB"pure_quanta"
PART_NUMBER"CH6223MEA01";
"B"
$PN"2"11;
"A"
$PN"1"12;
%"Q_CAP"
"1","(-4075,2400)","0","pure_quanta","I24";
;
LOCATION"PC557_4"
$SEC"1"
CDS_SEC"1"
MATERIAL"X6S"
PACK_TYPE"C0805"
VOLTAGE"16V"
TOLERANCE"20%"
VALUE"22UF"
CDS_LIB"pure_quanta"
PART_NUMBER"CH6223MEA01";
"B"
$PN"2"11;
"A"
$PN"1"12;
%"UNIVERSAL_GND"
"1","(-4375,3925)","0","pure_quanta_power","I25";
;
CDS_LIB"pure_quanta_power"
HDL_POWER"GND";
"A"3;
%"Q_RES"
"1","(-4050,3850)","0","pure_quanta","I26";
;
LOCATION"PR350"
$SEC"1"
CDS_SEC"1"
PACK_TYPE"0402LF"
VALUE"0"
TOLERANCE"5%"
MATERIAL"CHIP"
WATTAGE"1/16W"
CDS_LIB"pure_quanta"
PART_NUMBER"CS00002JB13";
"B"
$PN"2"27;
"A"
$PN"1"13;
%"Q_CAP"
"1","(-7675,4525)","0","pure_quanta","I27";
;
LOCATION"PC544_3"
$SEC"1"
CDS_SEC"1"
MATERIAL"X7R"
TOLERANCE"10%"
VALUE"0.1UF"
VOLTAGE"25V"
PACK_TYPE"0402"
CDS_LIB"pure_quanta"
PART_NUMBER"CH4104K1B00";
"B"
$PN"2"4;
"A"
$PN"1"46;
%"UNIVERSAL_GND"
"1","(-7675,4250)","0","pure_quanta_power","I28";
;
CDS_LIB"pure_quanta_power"
HDL_POWER"GND";
"A"4;
%"UNIVERSAL_GND"
"1","(-7600,950)","0","pure_quanta_power","I3";
;
CDS_LIB"pure_quanta_power"
HDL_POWER"GND";
"A"5;
%"UNIVERSAL_GND"
"1","(-7350,4325)","0","pure_quanta_power","I30";
;
CDS_LIB"pure_quanta_power"
HDL_POWER"GND";
"A"6;
%"Q_RES"
"1","(-7025,4500)","0","pure_quanta","I33";
;
LOCATION"PR346"
$SEC"1"
CDS_SEC"1"
PACK_TYPE"0402LF"
VALUE"8.87K"
TOLERANCE"1%"
MATERIAL"EMPTY"
WATTAGE"1/16W"
CDS_LIB"pure_quanta"
PART_NUMBER"CS28872FB01";
"B"
$PN"2"45;
"A"
$PN"1"6;
%"UNIVERSAL_GND"
"1","(-7350,4950)","0","pure_quanta_power","I34";
;
CDS_LIB"pure_quanta_power"
HDL_POWER"GND";
"A"7;
%"Q_CAP"
"1","(-7350,5150)","0","pure_quanta","I36";
;
LOCATION"PC546"
$SEC"1"
CDS_SEC"1"
MATERIAL"X6S"
TOLERANCE"10%"
VALUE"2.2UF"
VOLTAGE"10V"
PACK_TYPE"C0402"
CDS_LIB"pure_quanta"
PART_NUMBER"CH5222KEB01";
"B"
$PN"2"7;
"A"
$PN"1"40;
%"Q_RES"
"2","(-7350,5650)","0","pure_quanta","I37";
;
LOCATION"PR344"
$SEC"1"
CDS_SEC"1"
VALUE"2.2"
TOLERANCE"1%"
MATERIAL"CHIP"
WATTAGE"1/16W"
PACK_TYPE"0402LF"
CDS_LIB"pure_quanta"
PART_NUMBER"CS-2202FB01";
"A"
$PN"1"19;
"B"
$PN"2"40;
%"ISL99390FRZTR5935"
"1","(-5850,4800)","0","pure_quanta","I38";
;
LOCATION"PU46"
$SEC"1"
CDS_SEC"1"
MATERIAL"IC"
PART_TYPE"SMLF"
VALUE"ISL99390FRZ-TR5935"
CDS_LIB"pure_quanta"
NEEDS_NO_SIZE"TRUE"
CDS_LMAN_SYM_OUTLINE"-300,700,250,-650"
PART_NUMBER"AL099390004";
"PGND2"
$PN"7_9-20_24"20;
"GL2"
$PN"41"38;
"GL1"
$PN"6"39;
"DNC"
$PN"31"44;
"EN"
$PN"35"40;
"PGND3"
$PN"40"20;
"VOS"
$PN"1"13;
"VIN2"
$PN"30"25;
"PGND1"
$PN"5"20;
"SW"
$PN"10_19"14;
"LSET"
$PN"37"45;
"IOUT"
$PN"38"43;
"TOUT_FLT"
$PN"36"42;
"PVCC"
$PN"4"19;
"PHASE"
$PN"32"15;
"VIN1"
$PN"25_29"25;
"BOOT"
$PN"33"16;
"AGND"
$PN"2"20;
"VCC"
$PN"3"40;
"REFIN"
$PN"39"46;
"PWM"
$PN"34"41;
%"UNIVERSAL_GND"
"1","(-7000,5400)","0","pure_quanta_power","I39";
;
CDS_LIB"pure_quanta_power"
HDL_POWER"GND";
"A"8;
%"UNIVERSAL_GND"
"1","(-7275,1025)","0","pure_quanta_power","I4";
;
CDS_LIB"pure_quanta_power"
HDL_POWER"GND";
"A"9;
%"Q_CAP"
"1","(-7000,5650)","0","pure_quanta","I40";
;
LOCATION"PC548_C0P0_3"
$SEC"1"
CDS_SEC"1"
MATERIAL"X6S"
TOLERANCE"10%"
VALUE"2.2UF"
VOLTAGE"10V"
PACK_TYPE"C0402"
CDS_LIB"pure_quanta"
PART_NUMBER"CH5222KEB01";
"B"
$PN"2"8;
"A"
$PN"1"19;
%"VCC_CORE"
"1","(-7350,6100)","0","pure_quanta_power","I41";
;
HDL_POWER"PVDDCR_CPU0_P0_PVCC"
CDS_LIB"pure_quanta_power";
"A"19;
%"UNIVERSAL_GND"
"1","(-5300,4025)","0","pure_quanta_power","I42";
;
CDS_LIB"pure_quanta_power"
HDL_POWER"GND";
"A"20;
%"Q_CAP"
"1","(-5225,5700)","0","pure_quanta","I43";
;
LOCATION"PC552_3"
$SEC"1"
CDS_SEC"1"
TOLERANCE"10%"
VOLTAGE"25V"
PACK_TYPE"0402"
VALUE"0.1UF"
MATERIAL"X7R"
CDS_LIB"pure_quanta"
PART_NUMBER"CH4104K1B00";
"B"
$PN"2"24;
"A"
$PN"1"25;
%"Q_RES"
"2","(-4375,4150)","0","pure_quanta","I44";
;
LOCATION"PR498"
$SEC"1"
CDS_SEC"1"
WATTAGE"1/8W"
MATERIAL"EMPTY"
VALUE"1.5"
PACK_TYPE"0402LF"
TOLERANCE"1%"
CDS_LIB"pure_quanta"
PART_NUMBER"CS-1504FB00";
"A"
$PN"1"37;
"B"
$PN"2"3;
%"Q_CAP"
"1","(-4375,4625)","0","pure_quanta","I45";
;
LOCATION"PC180"
$SEC"1"
CDS_SEC"1"
VOLTAGE"50V"
PACK_TYPE"C0402"
MATERIAL"EMPTY"
TOLERANCE"10%"
VALUE"560PF"
CDS_LIB"pure_quanta"
PART_NUMBER"CH1566K1B09";
"B"
$PN"2"37;
"A"
$PN"1"14;
%"Q_RES"
"1","(-4450,5150)","0","pure_quanta","I46";
;
LOCATION"PR348"
$SEC"1"
CDS_SEC"1"
WATTAGE"1/16W"
PACK_TYPE"0402LF"
TOLERANCE"1%"
MATERIAL"CHIP"
VALUE"5.6"
CDS_LIB"pure_quanta"
PART_NUMBER"CS-5602FB01";
"B"
$PN"2"28;
"A"
$PN"1"16;
%"Q_CAP"
"1","(-4875,5700)","0","pure_quanta","I47";
;
LOCATION"PC550_3"
$SEC"1"
CDS_SEC"1"
PACK_TYPE"C0402"
MATERIAL"X6S"
TOLERANCE"10%"
VALUE"1UF"
VOLTAGE"25V"
CDS_LIB"pure_quanta"
PART_NUMBER"CH5104KEB02";
"B"
$PN"2"24;
"A"
$PN"1"25;
%"Q_CAP"
"1","(-4550,5700)","0","pure_quanta","I48";
;
LOCATION"PC554_3"
$SEC"1"
CDS_SEC"1"
MATERIAL"X6S"
PACK_TYPE"C0805"
VOLTAGE"16V"
TOLERANCE"20%"
VALUE"22UF"
CDS_LIB"pure_quanta"
PART_NUMBER"CH6223MEA01";
"B"
$PN"2"24;
"A"
$PN"1"25;
%"Q_CAP"
"1","(-4225,5700)","0","pure_quanta","I49";
;
LOCATION"PC556_3"
$SEC"1"
CDS_SEC"1"
PACK_TYPE"C0805"
VOLTAGE"16V"
VALUE"22UF"
MATERIAL"X6S"
TOLERANCE"20%"
CDS_LIB"pure_quanta"
PART_NUMBER"CH6223MEA01";
"B"
$PN"2"24;
"A"
$PN"1"25;
%"UNIVERSAL_GND"
"1","(-7250,1650)","0","pure_quanta_power","I5";
;
CDS_LIB"pure_quanta_power"
HDL_POWER"GND";
"A"10;
%"Q_RES"
"1","(-3875,600)","0","pure_quanta","I50";
;
LOCATION"PR351"
$SEC"1"
CDS_SEC"1"
PACK_TYPE"0402LF"
VALUE"0"
TOLERANCE"5%"
MATERIAL"CHIP"
WATTAGE"1/16W"
CDS_LIB"pure_quanta"
PART_NUMBER"CS00002JB13";
"B"
$PN"2"23;
"A"
$PN"1"47;
%"Q_INDUCTOR4P_14"
"1","(-2700,1375)","0","pure_quanta","I52";
;
LOCATION"PL60"
$SEC"1"
CDS_SEC"1"
PART_TYPE"SMLF"
MATERIAL"IND"
VALUE"150NH"
CDS_LIB"pure_quanta"
NEEDS_NO_SIZE"TRUE"
PART_NUMBER"CV+15^0TZ04";
"1"
$PN"1"33;
"4"
$PN"4"23;
"3"
$PN"3"21;
"2"
$PN"2"36;
%"Q_CAP"
"1","(-3400,1725)","0","pure_quanta","I53";
;
LOCATION"PC561"
$SEC"1"
CDS_SEC"1"
MATERIAL"X7R"
TOLERANCE"10%"
VALUE"0.22UF"
VOLTAGE"16V"
PACK_TYPE"0402"
CDS_LIB"pure_quanta"
PART_NUMBER"CH4223K1B00";
"B"
$PN"2"31;
"A"
$PN"1"30;
%"UNIVERSAL_GND"
"1","(-3700,2050)","0","pure_quanta_power","I54";
;
CDS_LIB"pure_quanta_power"
HDL_POWER"GND";
"A"11;
%"Q_CAP"
"1","(-3700,2400)","0","pure_quanta","I55";
;
LOCATION"PC559_4"
$SEC"1"
CDS_SEC"1"
MATERIAL"X6S"
VALUE"22UF"
VOLTAGE"16V"
TOLERANCE"20%"
PACK_TYPE"C0805"
CDS_LIB"pure_quanta"
PART_NUMBER"CH6223MEA01";
"B"
$PN"2"11;
"A"
$PN"1"12;
%"VCC_CORE"
"1","(-3700,2700)","0","pure_quanta_power","I56";
;
HDL_POWER"SW_P12V_AUX_PVDDCR_CPU0_P0_FLT"
CDS_LIB"pure_quanta_power";
"A"12;
%"UNIVERSAL_GND"
"1","(-1875,1050)","0","pure_quanta_power","I57";
;
CDS_LIB"pure_quanta_power"
HDL_POWER"GND";
"A"21;
%"Q_CAP"
"1","(-1300,1325)","0","pure_quanta","I58";
;
LOCATION"PC563_4"
$SEC"1"
CDS_SEC"1"
VOLTAGE"4V"
VALUE"22UF"
TOLERANCE"20%"
MATERIAL"X6S"
PACK_TYPE"C0805"
CDS_LIB"pure_quanta"
PART_NUMBER"CH622KMEA03";
"B"
$PN"2"22;
"A"
$PN"1"23;
%"UNIVERSAL_GND"
"1","(-800,825)","0","pure_quanta_power","I59";
;
CDS_LIB"pure_quanta_power"
HDL_POWER"GND";
"A"22;
%"Q_CAP"
"1","(-7250,1850)","0","pure_quanta","I6";
;
LOCATION"PC547"
$SEC"1"
CDS_SEC"1"
MATERIAL"X6S"
TOLERANCE"10%"
VALUE"2.2UF"
VOLTAGE"10V"
PACK_TYPE"C0402"
CDS_LIB"pure_quanta"
PART_NUMBER"CH5222KEB01";
"B"
$PN"2"10;
"A"
$PN"1"50;
%"Q_CAP"
"1","(-800,1325)","0","pure_quanta","I60";
;
LOCATION"PC565_4"
$SEC"1"
CDS_SEC"1"
VOLTAGE"4V"
VALUE"22UF"
TOLERANCE"20%"
MATERIAL"X6S"
PACK_TYPE"C0805"
CDS_LIB"pure_quanta"
PART_NUMBER"CH622KMEA03";
"B"
$PN"2"22;
"A"
$PN"1"23;
%"VCC_CORE"
"1","(-800,1650)","0","pure_quanta_power","I61";
;
HDL_POWER"PVDDCR_CPU0_P0"
CDS_LIB"pure_quanta_power";
"A"23;
%"Q_CAP"
"1","(-3450,5025)","0","pure_quanta","I63";
;
LOCATION"PC560"
$SEC"1"
CDS_SEC"1"
MATERIAL"X7R"
TOLERANCE"10%"
VALUE"0.22UF"
VOLTAGE"16V"
PACK_TYPE"0402"
CDS_LIB"pure_quanta"
PART_NUMBER"CH4223K1B00";
"B"
$PN"2"15;
"A"
$PN"1"28;
%"Q_INDUCTOR4P_14"
"1","(-2725,4675)","0","pure_quanta","I64";
;
LOCATION"PL59"
$SEC"1"
CDS_SEC"1"
PART_TYPE"SMLF"
MATERIAL"IND"
VALUE"150NH"
CDS_LIB"pure_quanta"
NEEDS_NO_SIZE"TRUE"
PART_NUMBER"CV+15^0TZ04";
"1"
$PN"1"14;
"4"
$PN"4"27;
"3"
$PN"3"34;
"2"
$PN"2"35;
%"UNIVERSAL_GND"
"1","(-3925,5375)","0","pure_quanta_power","I65";
;
CDS_LIB"pure_quanta_power"
HDL_POWER"GND";
"A"24;
%"Q_CAP"
"1","(-3925,5700)","0","pure_quanta","I66";
;
LOCATION"PC558_3"
$SEC"1"
CDS_SEC"1"
MATERIAL"X6S"
PACK_TYPE"C0805"
TOLERANCE"20%"
VALUE"22UF"
VOLTAGE"16V"
CDS_LIB"pure_quanta"
PART_NUMBER"CH6223MEA01";
"B"
$PN"2"24;
"A"
$PN"1"25;
%"VCC_CORE"
"1","(-3925,6000)","0","pure_quanta_power","I67";
;
HDL_POWER"SW_P12V_AUX_PVDDCR_CPU0_P0_FLT"
CDS_LIB"pure_quanta_power";
"A"25;
%"UNIVERSAL_GND"
"1","(-975,4275)","0","pure_quanta_power","I69";
;
CDS_LIB"pure_quanta_power"
HDL_POWER"GND";
"A"26;
%"Q_CAP"
"1","(-1400,4625)","0","pure_quanta","I70";
;
LOCATION"PC562_3"
$SEC"1"
CDS_SEC"1"
VOLTAGE"4V"
VALUE"22UF"
TOLERANCE"20%"
MATERIAL"X6S"
PACK_TYPE"C0805"
CDS_LIB"pure_quanta"
PART_NUMBER"CH622KMEA03";
"B"
$PN"2"26;
"A"
$PN"1"27;
%"Q_CAP"
"1","(-975,4625)","0","pure_quanta","I71";
;
LOCATION"PC564_3"
$SEC"1"
CDS_SEC"1"
VOLTAGE"4V"
VALUE"22UF"
TOLERANCE"20%"
MATERIAL"X6S"
PACK_TYPE"C0805"
CDS_LIB"pure_quanta"
PART_NUMBER"CH622KMEA03";
"B"
$PN"2"26;
"A"
$PN"1"27;
%"VCC_CORE"
"1","(-975,4950)","0","pure_quanta_power","I72";
;
HDL_POWER"PVDDCR_CPU0_P0"
CDS_LIB"pure_quanta_power";
"A"27;
%"ISL99390FRZTR5935"
"1","(-5775,1500)","0","pure_quanta","I9";
;
LOCATION"PU47"
$SEC"1"
CDS_SEC"1"
PART_TYPE"SMLF"
MATERIAL"IC"
VALUE"ISL99390FRZ-TR5935"
CDS_LIB"pure_quanta"
NEEDS_NO_SIZE"TRUE"
CDS_LMAN_SYM_OUTLINE"-300,700,250,-650"
PART_NUMBER"AL099390004";
"PGND2"
$PN"7_9-20_24"18;
"GL2"
$PN"41"49;
"GL1"
$PN"6"48;
"DNC"
$PN"31"53;
"EN"
$PN"35"50;
"PGND3"
$PN"40"18;
"VOS"
$PN"1"47;
"VIN2"
$PN"30"12;
"PGND1"
$PN"5"18;
"SW"
$PN"10_19"33;
"LSET"
$PN"37"54;
"IOUT"
$PN"38"51;
"TOUT_FLT"
$PN"36"52;
"PVCC"
$PN"4"17;
"PHASE"
$PN"32"31;
"VIN1"
$PN"25_29"12;
"BOOT"
$PN"33"29;
"AGND"
$PN"2"18;
"VCC"
$PN"3"50;
"REFIN"
$PN"39"56;
"PWM"
$PN"34"55;
END.
